(kicad_pcb
	(version 20260206)
	(generator "pcbnew")
	(generator_version "10.0")
	(general
		(thickness 1.6)
		(legacy_teardrops no)
	)
	(paper "A4")
	(title_block
		(title "Wiwynn_Tioga_Pass_MB.brd")
		(comment 1 "Tioga Pass / footprints 4205-4211 of 4770")
	)
	(layers
		(0 "F.Cu" signal "TOP")
		(4 "In1.Cu" signal "L2GND")
		(6 "In2.Cu" signal "L3")
		(8 "In3.Cu" signal "L4GND")
		(10 "In4.Cu" signal "L5")
		(12 "In5.Cu" signal "L6GND")
		(14 "In6.Cu" signal "L7VCC")
		(16 "In7.Cu" signal "L8VCC")
		(18 "In8.Cu" signal "L9GND")
		(20 "In9.Cu" signal "L10")
		(22 "In10.Cu" signal "L11GND")
		(24 "In11.Cu" signal "L12")
		(26 "In12.Cu" signal "L13GND")
		(2 "B.Cu" signal "BOTTOM")
		(9 "F.Adhes" user "F.Adhesive")
		(11 "B.Adhes" user "B.Adhesive")
		(13 "F.Paste" user "Package Geometry/Pastemask Top")
		(15 "B.Paste" user "Package Geometry/Pastemask Bottom")
		(5 "F.SilkS" user "Ref Des/Silkscreen Top")
		(7 "B.SilkS" user "Ref Des/Silkscreen Bottom")
		(1 "F.Mask" user "Board Geometry/Soldermask Top")
		(3 "B.Mask" user "Board Geometry/Soldermask Bottom")
		(17 "Dwgs.User" user "User.Drawings")
		(19 "Cmts.User" user "User.Comments")
		(21 "Eco1.User" user "User.Eco1")
		(23 "Eco2.User" user "User.Eco2")
		(25 "Edge.Cuts" user "Board Geometry/Outline")
		(27 "Margin" user)
		(31 "F.CrtYd" user "Package Geometry/Place Bound Top")
		(29 "B.CrtYd" user "Package Geometry/Place Bound Bottom")
		(35 "F.Fab" user "Ref Des/Assembly Top")
		(33 "B.Fab" user "Ref Des/Assembly Bottom")
	)
	(footprint ""
		(layer "B.Cu")
		(at 406.654 -27.178 90)
		(property "Reference" "R25W59"
			(at 0.8382 -0.67818 90)
			(unlocked yes)
			(layer "B.SilkS")
			(effects
				(font
					(size 0.4064 0.254)
					(thickness 0.1524)
				)
				(justify left mirror)
			)
		)
		(property "Value" ""
			(at 0 0 90)
			(layer "B.Fab")
			(effects
				(font
					(size 1.27 1.27)
				)
				(justify mirror)
			)
		)
		(duplicate_pad_numbers_are_jumpers no)
		(fp_poly
			(pts
				(xy 0.2794 -0.1016) (xy -0.2794 -0.1016) (xy -0.2794 0.9906) (xy 0.2794 0.9906)
			)
			(stroke
				(width 0)
				(type default)
			)
			(fill no)
			(layer "B.CrtYd")
		)
		(fp_line
			(start 0.2794 -0.1016)
			(end 0.2794 0.9906)
			(stroke
				(width 0.1)
				(type default)
			)
			(layer "B.Fab")
		)
		(fp_line
			(start -0.2794 -0.1016)
			(end 0.2794 -0.1016)
			(stroke
				(width 0.1)
				(type default)
			)
			(layer "B.Fab")
		)
		(fp_line
			(start 0.2794 0.9906)
			(end -0.2794 0.9906)
			(stroke
				(width 0.1)
				(type default)
			)
			(layer "B.Fab")
		)
		(fp_line
			(start -0.2794 0.9906)
			(end -0.2794 -0.1016)
			(stroke
				(width 0.1)
				(type default)
			)
			(layer "B.Fab")
		)
		(pad "1" smd rect
			(at 0 0 270)
			(size 0.508 0.508)
			(layers "B.Cu" "B.Mask" "B.Paste")
			(net "P3V3_STBY")
		)
		(pad "2" smd rect
			(at 0 0.889 270)
			(size 0.508 0.508)
			(layers "B.Cu" "B.Mask" "B.Paste")
			(net "VCCBAT_TW12")
		)
		(zone
			(layer "B.Cu")
			(hatch none 0.5)
			(connect_pads
				(clearance 0)
			)
			(min_thickness 0.25)
			(keepout
				(tracks allowed)
				(vias not_allowed)
				(pads allowed)
				(copperpour not_allowed)
				(footprints allowed)
			)
			(placement
				(enabled no)
				(sheetname "")
			)
			(fill
				(thermal_gap 0.5)
				(thermal_bridge_width 0.5)
				(island_removal_mode 0)
			)
			(polygon
				(pts
					(xy 406.908 -27.432) (xy 406.908 -26.924) (xy 407.289 -26.924) (xy 407.289 -27.432)
				)
			)
		)
		(zone
			(layer "B.Cu")
			(hatch none 0.5)
			(connect_pads
				(clearance 0)
			)
			(min_thickness 0.25)
			(keepout
				(tracks not_allowed)
				(vias allowed)
				(pads allowed)
				(copperpour not_allowed)
				(footprints allowed)
			)
			(placement
				(enabled no)
				(sheetname "")
			)
			(fill
				(thermal_gap 0.5)
				(thermal_bridge_width 0.5)
				(island_removal_mode 0)
			)
			(polygon
				(pts
					(xy 407.289 -27.432) (xy 407.289 -26.924) (xy 406.908 -26.924) (xy 406.908 -27.432)
				)
			)
		)
	)
	(footprint ""
		(layer "B.Cu")
		(at 17.526 -73.406 180)
		(property "Reference" "C9P17"
			(at 0 0 0)
			(layer "B.SilkS")
			(hide yes)
			(effects
				(font
					(size 1.27 1.27)
				)
				(justify mirror)
			)
		)
		(property "Value" ""
			(at 0 0 0)
			(layer "B.Fab")
			(effects
				(font
					(size 1.27 1.27)
				)
				(justify mirror)
			)
		)
		(duplicate_pad_numbers_are_jumpers no)
		(fp_rect
			(start -0.3048 0.9906)
			(end 0.3048 -0.1016)
			(stroke
				(width 0)
				(type default)
			)
			(fill no)
			(layer "B.CrtYd")
		)
		(fp_line
			(start 0.3048 0.9906)
			(end -0.3048 0.9906)
			(stroke
				(width 0.1)
				(type default)
			)
			(layer "B.Fab")
		)
		(fp_line
			(start 0.3048 -0.1016)
			(end 0.3048 0.9906)
			(stroke
				(width 0.1)
				(type default)
			)
			(layer "B.Fab")
		)
		(fp_line
			(start -0.3048 0.9906)
			(end -0.3048 -0.1016)
			(stroke
				(width 0.1)
				(type default)
			)
			(layer "B.Fab")
		)
		(fp_line
			(start -0.3048 -0.1016)
			(end 0.3048 -0.1016)
			(stroke
				(width 0.1)
				(type default)
			)
			(layer "B.Fab")
		)
		(pad "1" smd rect
			(at 0 0)
			(size 0.508 0.508)
			(layers "B.Cu" "B.Mask" "B.Paste")
			(net "A_HSC_MON")
		)
		(pad "2" smd rect
			(at 0 0.889)
			(size 0.508 0.508)
			(layers "B.Cu" "B.Mask" "B.Paste")
			(net "AGND_HSC")
		)
		(zone
			(layer "B.Cu")
			(hatch none 0.5)
			(connect_pads
				(clearance 0)
			)
			(min_thickness 0.25)
			(keepout
				(tracks not_allowed)
				(vias allowed)
				(pads allowed)
				(copperpour not_allowed)
				(footprints allowed)
			)
			(placement
				(enabled no)
				(sheetname "")
			)
			(fill
				(thermal_gap 0.5)
				(thermal_bridge_width 0.5)
				(island_removal_mode 0)
			)
			(polygon
				(pts
					(xy 17.78 -74.041) (xy 17.272 -74.041) (xy 17.272 -73.66) (xy 17.78 -73.66)
				)
			)
		)
		(zone
			(layer "B.Cu")
			(hatch none 0.5)
			(connect_pads
				(clearance 0)
			)
			(min_thickness 0.25)
			(keepout
				(tracks allowed)
				(vias not_allowed)
				(pads allowed)
				(copperpour not_allowed)
				(footprints allowed)
			)
			(placement
				(enabled no)
				(sheetname "")
			)
			(fill
				(thermal_gap 0.5)
				(thermal_bridge_width 0.5)
				(island_removal_mode 0)
			)
			(polygon
				(pts
					(xy 17.78 -74.041) (xy 17.272 -74.041) (xy 17.272 -73.66) (xy 17.78 -73.66)
				)
			)
		)
	)
	(footprint ""
		(layer "B.Cu")
		(at 476.25 -147.193 -90)
		(property "Reference" "R6W16"
			(at 0.8382 -0.67818 270)
			(unlocked yes)
			(layer "B.SilkS")
			(effects
				(font
					(size 0.4064 0.254)
					(thickness 0.1524)
				)
				(justify left mirror)
			)
		)
		(property "Value" ""
			(at 0 0 90)
			(layer "B.Fab")
			(effects
				(font
					(size 1.27 1.27)
				)
				(justify mirror)
			)
		)
		(duplicate_pad_numbers_are_jumpers no)
		(fp_poly
			(pts
				(xy 0.2794 -0.1016) (xy -0.2794 -0.1016) (xy -0.2794 0.9906) (xy 0.2794 0.9906)
			)
			(stroke
				(width 0)
				(type default)
			)
			(fill no)
			(layer "B.CrtYd")
		)
		(fp_line
			(start -0.2794 0.9906)
			(end -0.2794 -0.1016)
			(stroke
				(width 0.1)
				(type default)
			)
			(layer "B.Fab")
		)
		(fp_line
			(start 0.2794 0.9906)
			(end -0.2794 0.9906)
			(stroke
				(width 0.1)
				(type default)
			)
			(layer "B.Fab")
		)
		(fp_line
			(start -0.2794 -0.1016)
			(end 0.2794 -0.1016)
			(stroke
				(width 0.1)
				(type default)
			)
			(layer "B.Fab")
		)
		(fp_line
			(start 0.2794 -0.1016)
			(end 0.2794 0.9906)
			(stroke
				(width 0.1)
				(type default)
			)
			(layer "B.Fab")
		)
		(pad "1" smd rect
			(at 0 0 90)
			(size 0.508 0.508)
			(layers "B.Cu" "B.Mask" "B.Paste")
			(net "P3V3_STBY")
		)
		(pad "2" smd rect
			(at 0 0.889 90)
			(size 0.508 0.508)
			(layers "B.Cu" "B.Mask" "B.Paste")
			(net "FM_SOL_UART_CH_SEL")
		)
		(zone
			(layer "B.Cu")
			(hatch none 0.5)
			(connect_pads
				(clearance 0)
			)
			(min_thickness 0.25)
			(keepout
				(tracks not_allowed)
				(vias allowed)
				(pads allowed)
				(copperpour not_allowed)
				(footprints allowed)
			)
			(placement
				(enabled no)
				(sheetname "")
			)
			(fill
				(thermal_gap 0.5)
				(thermal_bridge_width 0.5)
				(island_removal_mode 0)
			)
			(polygon
				(pts
					(xy 475.615 -146.939) (xy 475.615 -147.447) (xy 475.996 -147.447) (xy 475.996 -146.939)
				)
			)
		)
		(zone
			(layer "B.Cu")
			(hatch none 0.5)
			(connect_pads
				(clearance 0)
			)
			(min_thickness 0.25)
			(keepout
				(tracks allowed)
				(vias not_allowed)
				(pads allowed)
				(copperpour not_allowed)
				(footprints allowed)
			)
			(placement
				(enabled no)
				(sheetname "")
			)
			(fill
				(thermal_gap 0.5)
				(thermal_bridge_width 0.5)
				(island_removal_mode 0)
			)
			(polygon
				(pts
					(xy 475.996 -146.939) (xy 475.996 -147.447) (xy 475.615 -147.447) (xy 475.615 -146.939)
				)
			)
		)
	)
	(footprint ""
		(layer "B.Cu")
		(at 104.394254 -85.06714)
		(property "Reference" "C8P4"
			(at 0 0 0)
			(layer "B.SilkS")
			(hide yes)
			(effects
				(font
					(size 1.27 1.27)
				)
				(justify mirror)
			)
		)
		(property "Value" ""
			(at 0 0 0)
			(layer "B.Fab")
			(effects
				(font
					(size 1.27 1.27)
				)
				(justify mirror)
			)
		)
		(duplicate_pad_numbers_are_jumpers no)
		(fp_poly
			(pts
				(xy 0.7239 -0.2159) (xy -0.7239 -0.2159) (xy -0.7239 1.9939) (xy 0.7239 1.9939)
			)
			(stroke
				(width 0)
				(type default)
			)
			(fill no)
			(layer "B.CrtYd")
		)
		(fp_line
			(start -0.7239 -0.2159)
			(end 0.7239 -0.2159)
			(stroke
				(width 0.1)
				(type default)
			)
			(layer "B.Fab")
		)
		(fp_line
			(start -0.7239 1.9939)
			(end -0.7239 -0.2159)
			(stroke
				(width 0.1)
				(type default)
			)
			(layer "B.Fab")
		)
		(fp_line
			(start 0.7239 -0.2159)
			(end 0.7239 1.9939)
			(stroke
				(width 0.1)
				(type default)
			)
			(layer "B.Fab")
		)
		(fp_line
			(start 0.7239 1.9939)
			(end -0.7239 1.9939)
			(stroke
				(width 0.1)
				(type default)
			)
			(layer "B.Fab")
		)
		(pad "1" smd rect
			(at 0 0 180)
			(size 1.27 1.016)
			(layers "B.Cu" "B.Mask" "B.Paste")
			(net "PVDDQ_KLM")
		)
		(pad "2" smd rect
			(at 0 1.778 180)
			(size 1.27 1.016)
			(layers "B.Cu" "B.Mask" "B.Paste")
			(net "GND")
		)
		(zone
			(layer "B.Cu")
			(hatch none 0.5)
			(connect_pads
				(clearance 0)
			)
			(min_thickness 0.25)
			(keepout
				(tracks not_allowed)
				(vias allowed)
				(pads allowed)
				(copperpour not_allowed)
				(footprints allowed)
			)
			(placement
				(enabled no)
				(sheetname "")
			)
			(fill
				(thermal_gap 0.5)
				(thermal_bridge_width 0.5)
				(island_removal_mode 0)
			)
			(polygon
				(pts
					(xy 105.029254 -84.55914) (xy 103.759254 -84.55914) (xy 103.759254 -83.79714) (xy 105.029254 -83.79714)
				)
			)
		)
	)
	(footprint ""
		(layer "B.Cu")
		(at 387.604 -16.383 90)
		(property "Reference" "R32W9"
			(at 0.8382 -0.67818 90)
			(unlocked yes)
			(layer "B.SilkS")
			(effects
				(font
					(size 0.4064 0.254)
					(thickness 0.1524)
				)
				(justify left mirror)
			)
		)
		(property "Value" ""
			(at 0 0 90)
			(layer "B.Fab")
			(effects
				(font
					(size 1.27 1.27)
				)
				(justify mirror)
			)
		)
		(duplicate_pad_numbers_are_jumpers no)
		(fp_poly
			(pts
				(xy 0.2794 -0.1016) (xy -0.2794 -0.1016) (xy -0.2794 0.9906) (xy 0.2794 0.9906)
			)
			(stroke
				(width 0)
				(type default)
			)
			(fill no)
			(layer "B.CrtYd")
		)
		(fp_line
			(start 0.2794 -0.1016)
			(end 0.2794 0.9906)
			(stroke
				(width 0.1)
				(type default)
			)
			(layer "B.Fab")
		)
		(fp_line
			(start -0.2794 -0.1016)
			(end 0.2794 -0.1016)
			(stroke
				(width 0.1)
				(type default)
			)
			(layer "B.Fab")
		)
		(fp_line
			(start 0.2794 0.9906)
			(end -0.2794 0.9906)
			(stroke
				(width 0.1)
				(type default)
			)
			(layer "B.Fab")
		)
		(fp_line
			(start -0.2794 0.9906)
			(end -0.2794 -0.1016)
			(stroke
				(width 0.1)
				(type default)
			)
			(layer "B.Fab")
		)
		(pad "1" smd rect
			(at 0 0 270)
			(size 0.508 0.508)
			(layers "B.Cu" "B.Mask" "B.Paste")
			(net "PD_SMB_M2_EN")
		)
		(pad "2" smd rect
			(at 0 0.889 270)
			(size 0.508 0.508)
			(layers "B.Cu" "B.Mask" "B.Paste")
			(net "GND")
		)
		(zone
			(layer "B.Cu")
			(hatch none 0.5)
			(connect_pads
				(clearance 0)
			)
			(min_thickness 0.25)
			(keepout
				(tracks allowed)
				(vias not_allowed)
				(pads allowed)
				(copperpour not_allowed)
				(footprints allowed)
			)
			(placement
				(enabled no)
				(sheetname "")
			)
			(fill
				(thermal_gap 0.5)
				(thermal_bridge_width 0.5)
				(island_removal_mode 0)
			)
			(polygon
				(pts
					(xy 387.858 -16.637) (xy 387.858 -16.129) (xy 388.239 -16.129) (xy 388.239 -16.637)
				)
			)
		)
		(zone
			(layer "B.Cu")
			(hatch none 0.5)
			(connect_pads
				(clearance 0)
			)
			(min_thickness 0.25)
			(keepout
				(tracks not_allowed)
				(vias allowed)
				(pads allowed)
				(copperpour not_allowed)
				(footprints allowed)
			)
			(placement
				(enabled no)
				(sheetname "")
			)
			(fill
				(thermal_gap 0.5)
				(thermal_bridge_width 0.5)
				(island_removal_mode 0)
			)
			(polygon
				(pts
					(xy 388.239 -16.637) (xy 388.239 -16.129) (xy 387.858 -16.129) (xy 387.858 -16.637)
				)
			)
		)
	)
	(footprint ""
		(layer "B.Cu")
		(at 369.145058 -77.096112 90)
		(property "Reference" "C3P48"
			(at 0 0 90)
			(layer "B.SilkS")
			(hide yes)
			(effects
				(font
					(size 1.27 1.27)
				)
				(justify mirror)
			)
		)
		(property "Value" ""
			(at 0 0 90)
			(layer "B.Fab")
			(effects
				(font
					(size 1.27 1.27)
				)
				(justify mirror)
			)
		)
		(duplicate_pad_numbers_are_jumpers no)
		(fp_rect
			(start 0.2794 0.9144)
			(end -0.2794 -0.1143)
			(stroke
				(width 0)
				(type default)
			)
			(fill no)
			(layer "B.CrtYd")
		)
		(fp_line
			(start 0.2794 -0.1143)
			(end -0.2794 -0.1143)
			(stroke
				(width 0.1)
				(type default)
			)
			(layer "B.Fab")
		)
		(fp_line
			(start -0.2794 -0.1143)
			(end -0.2794 0.9144)
			(stroke
				(width 0.1)
				(type default)
			)
			(layer "B.Fab")
		)
		(fp_line
			(start 0.2794 0.9144)
			(end 0.2794 -0.1143)
			(stroke
				(width 0.1)
				(type default)
			)
			(layer "B.Fab")
		)
		(fp_line
			(start -0.2794 0.9144)
			(end 0.2794 0.9144)
			(stroke
				(width 0.1)
				(type default)
			)
			(layer "B.Fab")
		)
		(pad "1" smd custom
			(at 0 0)
			(size 0.10414 0.10414)
			(layers "B.Cu" "B.Mask" "B.Paste")
			(net "P3V3_STBY")
			(options
				(clearance outline)
				(anchor circle)
			)
			(primitives
				(gr_poly
					(pts
						(xy -0.20828 -0.08636) (xy -0.20828 0.08636) (xy -0.08636 0.20828) (xy 0.086614 0.20828) (xy 0.20828 0.086614)
						(xy 0.20828 -0.08636) (xy 0.08636 -0.20828) (xy -0.08636 -0.20828)
					)
					(width 0)
					(fill yes)
				)
			)
		)
		(pad "2" smd custom
			(at 0 0.8001)
			(size 0.10414 0.10414)
			(layers "B.Cu" "B.Mask" "B.Paste")
			(net "GND")
			(options
				(clearance outline)
				(anchor circle)
			)
			(primitives
				(gr_poly
					(pts
						(xy -0.20828 -0.08636) (xy -0.20828 0.08636) (xy -0.08636 0.20828) (xy 0.086614 0.20828) (xy 0.20828 0.086614)
						(xy 0.20828 -0.08636) (xy 0.08636 -0.20828) (xy -0.08636 -0.20828)
					)
					(width 0)
					(fill yes)
				)
			)
		)
		(zone
			(layer "B.Cu")
			(hatch none 0.5)
			(connect_pads
				(clearance 0)
			)
			(min_thickness 0.25)
			(keepout
				(tracks allowed)
				(vias not_allowed)
				(pads allowed)
				(copperpour not_allowed)
				(footprints allowed)
			)
			(placement
				(enabled no)
				(sheetname "")
			)
			(fill
				(thermal_gap 0.5)
				(thermal_bridge_width 0.5)
				(island_removal_mode 0)
			)
			(polygon
				(pts
					(xy 369.354608 -77.183742) (xy 369.735608 -77.183742) (xy 369.735608 -77.008482) (xy 369.354608 -77.008228)
				)
			)
		)
		(zone
			(layer "B.Cu")
			(hatch none 0.5)
			(connect_pads
				(clearance 0)
			)
			(min_thickness 0.25)
			(keepout
				(tracks not_allowed)
				(vias allowed)
				(pads allowed)
				(copperpour not_allowed)
				(footprints allowed)
			)
			(placement
				(enabled no)
				(sheetname "")
			)
			(fill
				(thermal_gap 0.5)
				(thermal_bridge_width 0.5)
				(island_removal_mode 0)
			)
			(polygon
				(pts
					(xy 369.354608 -77.183742) (xy 369.735608 -77.183742) (xy 369.735608 -77.008482) (xy 369.354608 -77.008228)
				)
			)
		)
	)
	(footprint ""
		(layer "B.Cu")
		(at 155.293568 -135.376412 90)
		(property "Reference" "C7M3"
			(at 0 0 90)
			(layer "B.SilkS")
			(hide yes)
			(effects
				(font
					(size 1.27 1.27)
				)
				(justify mirror)
			)
		)
		(property "Value" ""
			(at 0 0 90)
			(layer "B.Fab")
			(effects
				(font
					(size 1.27 1.27)
				)
				(justify mirror)
			)
		)
		(duplicate_pad_numbers_are_jumpers no)
		(fp_rect
			(start 0.4953 1.6002)
			(end -0.4953 -0.2032)
			(stroke
				(width 0)
				(type default)
			)
			(fill no)
			(layer "B.CrtYd")
		)
		(fp_line
			(start 0.4953 -0.2032)
			(end -0.4953 -0.2032)
			(stroke
				(width 0.1)
				(type default)
			)
			(layer "B.Fab")
		)
		(fp_line
			(start -0.4953 -0.2032)
			(end -0.4953 1.6002)
			(stroke
				(width 0.1)
				(type default)
			)
			(layer "B.Fab")
		)
		(fp_line
			(start 0.4953 1.6002)
			(end 0.4953 -0.2032)
			(stroke
				(width 0.1)
				(type default)
			)
			(layer "B.Fab")
		)
		(fp_line
			(start -0.4953 1.6002)
			(end 0.4953 1.6002)
			(stroke
				(width 0.1)
				(type default)
			)
			(layer "B.Fab")
		)
		(pad "1" smd rect
			(at 0 0 270)
			(size 0.762 0.889)
			(layers "B.Cu" "B.Mask" "B.Paste")
			(net "PVPP_KLM")
		)
		(pad "2" smd rect
			(at 0 1.397 270)
			(size 0.762 0.889)
			(layers "B.Cu" "B.Mask" "B.Paste")
			(net "GND")
		)
		(zone
			(layer "B.Cu")
			(hatch none 0.5)
			(connect_pads
				(clearance 0)
			)
			(min_thickness 0.25)
			(keepout
				(tracks not_allowed)
				(vias allowed)
				(pads allowed)
				(copperpour not_allowed)
				(footprints allowed)
			)
			(placement
				(enabled no)
				(sheetname "")
			)
			(fill
				(thermal_gap 0.5)
				(thermal_bridge_width 0.5)
				(island_removal_mode 0)
			)
			(polygon
				(pts
					(xy 156.246068 -135.757412) (xy 155.738068 -135.757412) (xy 155.738068 -134.995412) (xy 156.246068 -134.995412)
				)
			)
		)
	)
)
